(kicad_pcb
	(version 20260206)
	(generator "pcbnew")
	(generator_version "10.0")
	(general
		(thickness 1.6)
		(legacy_teardrops no)
	)
	(paper "A4")
	(title_block
		(title "01162023_DA0F0TEBIF0_F0T_Expander_BD_F_brd_V02_OCP.brd")
		(comment 1 "Grand Teton / footprints 328-334 of 9728")
	)
	(layers
		(0 "F.Cu" signal "TOP")
		(4 "In1.Cu" signal "GND")
		(6 "In2.Cu" signal "VCC")
		(8 "In3.Cu" signal "VCC1")
		(10 "In4.Cu" signal "GND1")
		(12 "In5.Cu" signal "IN1")
		(14 "In6.Cu" signal "GND2")
		(16 "In7.Cu" signal "IN2")
		(18 "In8.Cu" signal "GND3")
		(20 "In9.Cu" signal "IN3")
		(22 "In10.Cu" signal "GND4")
		(24 "In11.Cu" signal "IN4")
		(26 "In12.Cu" signal "GND5")
		(28 "In13.Cu" signal "IN5")
		(30 "In14.Cu" signal "GND6")
		(32 "In15.Cu" signal "IN6")
		(34 "In16.Cu" signal "GND7")
		(2 "B.Cu" signal "BOTTOM")
		(9 "F.Adhes" user "F.Adhesive")
		(11 "B.Adhes" user "B.Adhesive")
		(13 "F.Paste" user "Package Geometry/Pastemask Top")
		(15 "B.Paste" user "Package Geometry/Pastemask Bottom")
		(5 "F.SilkS" user "Ref Des/Silkscreen Top")
		(7 "B.SilkS" user "Ref Des/Silkscreen Bottom")
		(1 "F.Mask" user "Board Geometry/Soldermask Top")
		(3 "B.Mask" user "Board Geometry/Soldermask Bottom")
		(17 "Dwgs.User" user "User.Drawings")
		(19 "Cmts.User" user "User.Comments")
		(21 "Eco1.User" user "User.Eco1")
		(23 "Eco2.User" user "User.Eco2")
		(25 "Edge.Cuts" user "Board Geometry/Outline")
		(27 "Margin" user)
		(31 "F.CrtYd" user "Package Geometry/Place Bound Top")
		(29 "B.CrtYd" user "Package Geometry/Place Bound Bottom")
		(35 "F.Fab" user "Ref Des/Assembly Top")
		(33 "B.Fab" user "Ref Des/Assembly Bottom")
	)
	(footprint ""
		(layer "F.Cu")
		(at 363.501432 -55.78475 -90)
		(property "Reference" "PD39"
			(at 4.07035 2.159762 90)
			(unlocked yes)
			(layer "F.SilkS")
			(effects
				(font
					(size 0.7874 0.5842)
					(thickness 0.1524)
				)
				(justify left)
			)
		)
		(property "Value" ""
			(at 0 0 270)
			(layer "F.Fab")
			(effects
				(font
					(size 1.27 1.27)
				)
			)
		)
		(duplicate_pad_numbers_are_jumpers no)
		(fp_line
			(start -3.400044 1.459992)
			(end -3.400044 -1.459992)
			(stroke
				(width 0.1524)
				(type default)
			)
			(layer "F.SilkS")
		)
		(fp_line
			(start 4.107942 1.459992)
			(end -3.400044 1.459992)
			(stroke
				(width 0.1524)
				(type default)
			)
			(layer "F.SilkS")
		)
		(fp_line
			(start -3.400044 -1.459992)
			(end 4.107942 -1.459992)
			(stroke
				(width 0.1524)
				(type default)
			)
			(layer "F.SilkS")
		)
		(fp_line
			(start 4.107942 -1.459992)
			(end 4.107942 1.459992)
			(stroke
				(width 0.1524)
				(type default)
			)
			(layer "F.SilkS")
		)
		(fp_poly
			(pts
				(xy 4.107942 -1.459992) (xy 4.107942 1.459992) (xy 3.308096 1.459992) (xy 3.308096 -1.459992)
			)
			(stroke
				(width 0)
				(type default)
			)
			(fill yes)
			(layer "F.SilkS")
		)
		(fp_line
			(start -2.29997 1.459992)
			(end -2.29997 -1.459992)
			(stroke
				(width 0.1)
				(type default)
			)
			(layer "F.Fab")
		)
		(fp_line
			(start 2.29997 1.459992)
			(end -2.29997 1.459992)
			(stroke
				(width 0.1)
				(type default)
			)
			(layer "F.Fab")
		)
		(fp_line
			(start -2.29997 -1.459992)
			(end 2.29997 -1.459992)
			(stroke
				(width 0.1)
				(type default)
			)
			(layer "F.Fab")
		)
		(fp_line
			(start 2.29997 -1.459992)
			(end 2.29997 1.459992)
			(stroke
				(width 0.1)
				(type default)
			)
			(layer "F.Fab")
		)
		(fp_text user "-"
			(at 5.4102 0.29845 90)
			(unlocked yes)
			(layer "F.SilkS")
			(effects
				(font
					(size 1.905 1.4224)
					(thickness 0.1524)
				)
				(justify left)
			)
		)
		(fp_text user "+"
			(at -4.7752 -0.12065 270)
			(unlocked yes)
			(layer "F.SilkS")
			(effects
				(font
					(size 1.905 1.4224)
					(thickness 0.1524)
				)
				(justify left)
			)
		)
		(fp_text user "-"
			(at 5.4102 0.29845 90)
			(unlocked yes)
			(layer "F.Fab")
			(effects
				(font
					(size 1.905 1.4224)
					(thickness 0.1524)
				)
				(justify left)
			)
		)
		(fp_text user "+"
			(at -4.7752 -0.12065 270)
			(unlocked yes)
			(layer "F.Fab")
			(effects
				(font
					(size 1.905 1.4224)
					(thickness 0.1524)
				)
				(justify left)
			)
		)
		(pad "A" smd rect
			(at -1.999996 0)
			(size 1.7018 2.5146)
			(layers "F.Cu" "F.Mask" "F.Paste")
			(net "GND")
		)
		(pad "C" smd rect
			(at 1.999996 0)
			(size 1.7018 2.5146)
			(layers "F.Cu" "F.Mask" "F.Paste")
			(net "P12V_SSD12_R")
		)
	)
	(footprint ""
		(layer "F.Cu")
		(at 353.594162 -34.248852)
		(property "Reference" "R5699"
			(at 0 0 0)
			(layer "F.SilkS")
			(hide yes)
			(effects
				(font
					(size 1.27 1.27)
				)
			)
		)
		(property "Value" ""
			(at 0 0 0)
			(layer "F.Fab")
			(effects
				(font
					(size 1.27 1.27)
				)
			)
		)
		(duplicate_pad_numbers_are_jumpers no)
		(fp_line
			(start -0.7874 -0.4064)
			(end 0.7874 -0.4064)
			(stroke
				(width 0.1524)
				(type default)
			)
			(layer "F.SilkS")
		)
		(fp_line
			(start -0.7874 0.4064)
			(end -0.7874 -0.4064)
			(stroke
				(width 0.1524)
				(type default)
			)
			(layer "F.SilkS")
		)
		(fp_line
			(start 0.7874 -0.4064)
			(end 0.7874 0.4064)
			(stroke
				(width 0.1524)
				(type default)
			)
			(layer "F.SilkS")
		)
		(fp_line
			(start 0.7874 0.4064)
			(end -0.7874 0.4064)
			(stroke
				(width 0.1524)
				(type default)
			)
			(layer "F.SilkS")
		)
		(fp_line
			(start -0.67945 -0.305054)
			(end -0.12065 -0.305054)
			(stroke
				(width 0.1)
				(type default)
			)
			(layer "F.Fab")
		)
		(fp_line
			(start -0.67945 0.3048)
			(end -0.67945 -0.305054)
			(stroke
				(width 0.1)
				(type default)
			)
			(layer "F.Fab")
		)
		(fp_line
			(start -0.12065 -0.305054)
			(end -0.12065 -0.2794)
			(stroke
				(width 0.1)
				(type default)
			)
			(layer "F.Fab")
		)
		(fp_line
			(start -0.12065 -0.2794)
			(end 0.12065 -0.2794)
			(stroke
				(width 0.1)
				(type default)
			)
			(layer "F.Fab")
		)
		(fp_line
			(start -0.12065 0.2794)
			(end -0.12065 0.3048)
			(stroke
				(width 0.1)
				(type default)
			)
			(layer "F.Fab")
		)
		(fp_line
			(start -0.12065 0.3048)
			(end -0.67945 0.3048)
			(stroke
				(width 0.1)
				(type default)
			)
			(layer "F.Fab")
		)
		(fp_line
			(start 0.120396 0.2794)
			(end -0.12065 0.2794)
			(stroke
				(width 0.1)
				(type default)
			)
			(layer "F.Fab")
		)
		(fp_line
			(start 0.120396 0.3048)
			(end 0.120396 0.2794)
			(stroke
				(width 0.1)
				(type default)
			)
			(layer "F.Fab")
		)
		(fp_line
			(start 0.12065 -0.3048)
			(end 0.67945 -0.3048)
			(stroke
				(width 0.1)
				(type default)
			)
			(layer "F.Fab")
		)
		(fp_line
			(start 0.12065 -0.2794)
			(end 0.12065 -0.3048)
			(stroke
				(width 0.1)
				(type default)
			)
			(layer "F.Fab")
		)
		(fp_line
			(start 0.67945 -0.3048)
			(end 0.67945 0.3048)
			(stroke
				(width 0.1)
				(type default)
			)
			(layer "F.Fab")
		)
		(fp_line
			(start 0.67945 0.3048)
			(end 0.120396 0.3048)
			(stroke
				(width 0.1)
				(type default)
			)
			(layer "F.Fab")
		)
		(pad "1" smd circle
			(at -0.40005 0)
			(size 0 0)
			(layers "F.Cu" "F.Mask" "F.Paste")
			(net "RST_SMB_SSD12_ISO_N")
		)
		(pad "2" smd circle
			(at 0.40005 0)
			(size 0 0)
			(layers "F.Cu" "F.Mask" "F.Paste")
			(net "P3V3_SSD12")
		)
	)
	(footprint ""
		(layer "F.Cu")
		(at 330.63434 -30.03169 180)
		(property "Reference" "C516"
			(at 0 0 180)
			(layer "F.SilkS")
			(hide yes)
			(effects
				(font
					(size 1.27 1.27)
				)
			)
		)
		(property "Value" ""
			(at 0 0 180)
			(layer "F.Fab")
			(effects
				(font
					(size 1.27 1.27)
				)
			)
		)
		(duplicate_pad_numbers_are_jumpers no)
		(fp_line
			(start 0.299974 0.150114)
			(end -0.299974 0.150114)
			(stroke
				(width 0.1)
				(type default)
			)
			(layer "F.Fab")
		)
		(fp_line
			(start 0.299974 -0.150114)
			(end 0.299974 0.150114)
			(stroke
				(width 0.1)
				(type default)
			)
			(layer "F.Fab")
		)
		(fp_line
			(start -0.299974 0.150114)
			(end -0.299974 -0.150114)
			(stroke
				(width 0.1)
				(type default)
			)
			(layer "F.Fab")
		)
		(fp_line
			(start -0.299974 -0.150114)
			(end 0.299974 -0.150114)
			(stroke
				(width 0.1)
				(type default)
			)
			(layer "F.Fab")
		)
		(pad "1" smd rect
			(at -0.2667 0 180)
			(size 0.3048 0.381)
			(layers "F.Cu" "F.Mask" "F.Paste")
			(net "P5E_PEX2_STN2_TX_DN<33>")
		)
		(pad "2" smd rect
			(at 0.2667 0 180)
			(size 0.3048 0.381)
			(layers "F.Cu" "F.Mask" "F.Paste")
			(net "P5E_PEX2_STN2_TX_C_DN<33>")
		)
	)
	(footprint ""
		(layer "F.Cu")
		(at 310.443626 -43.85691)
		(property "Reference" "R619"
			(at 0 0 0)
			(layer "F.SilkS")
			(hide yes)
			(effects
				(font
					(size 1.27 1.27)
				)
			)
		)
		(property "Value" ""
			(at 0 0 0)
			(layer "F.Fab")
			(effects
				(font
					(size 1.27 1.27)
				)
			)
		)
		(duplicate_pad_numbers_are_jumpers no)
		(fp_line
			(start -0.7874 -0.4064)
			(end 0.7874 -0.4064)
			(stroke
				(width 0.1524)
				(type default)
			)
			(layer "F.SilkS")
		)
		(fp_line
			(start -0.7874 0.4064)
			(end -0.7874 -0.4064)
			(stroke
				(width 0.1524)
				(type default)
			)
			(layer "F.SilkS")
		)
		(fp_line
			(start 0.7874 -0.4064)
			(end 0.7874 0.4064)
			(stroke
				(width 0.1524)
				(type default)
			)
			(layer "F.SilkS")
		)
		(fp_line
			(start 0.7874 0.4064)
			(end -0.7874 0.4064)
			(stroke
				(width 0.1524)
				(type default)
			)
			(layer "F.SilkS")
		)
		(fp_line
			(start -0.67945 -0.305054)
			(end -0.12065 -0.305054)
			(stroke
				(width 0.1)
				(type default)
			)
			(layer "F.Fab")
		)
		(fp_line
			(start -0.67945 0.3048)
			(end -0.67945 -0.305054)
			(stroke
				(width 0.1)
				(type default)
			)
			(layer "F.Fab")
		)
		(fp_line
			(start -0.12065 -0.305054)
			(end -0.12065 -0.2794)
			(stroke
				(width 0.1)
				(type default)
			)
			(layer "F.Fab")
		)
		(fp_line
			(start -0.12065 -0.2794)
			(end 0.12065 -0.2794)
			(stroke
				(width 0.1)
				(type default)
			)
			(layer "F.Fab")
		)
		(fp_line
			(start -0.12065 0.2794)
			(end -0.12065 0.3048)
			(stroke
				(width 0.1)
				(type default)
			)
			(layer "F.Fab")
		)
		(fp_line
			(start -0.12065 0.3048)
			(end -0.67945 0.3048)
			(stroke
				(width 0.1)
				(type default)
			)
			(layer "F.Fab")
		)
		(fp_line
			(start 0.120396 0.2794)
			(end -0.12065 0.2794)
			(stroke
				(width 0.1)
				(type default)
			)
			(layer "F.Fab")
		)
		(fp_line
			(start 0.120396 0.3048)
			(end 0.120396 0.2794)
			(stroke
				(width 0.1)
				(type default)
			)
			(layer "F.Fab")
		)
		(fp_line
			(start 0.12065 -0.3048)
			(end 0.67945 -0.3048)
			(stroke
				(width 0.1)
				(type default)
			)
			(layer "F.Fab")
		)
		(fp_line
			(start 0.12065 -0.2794)
			(end 0.12065 -0.3048)
			(stroke
				(width 0.1)
				(type default)
			)
			(layer "F.Fab")
		)
		(fp_line
			(start 0.67945 -0.3048)
			(end 0.67945 0.3048)
			(stroke
				(width 0.1)
				(type default)
			)
			(layer "F.Fab")
		)
		(fp_line
			(start 0.67945 0.3048)
			(end 0.120396 0.3048)
			(stroke
				(width 0.1)
				(type default)
			)
			(layer "F.Fab")
		)
		(pad "1" smd circle
			(at -0.40005 0)
			(size 0 0)
			(layers "F.Cu" "F.Mask" "F.Paste")
			(net "SSD10_ADC_A1")
		)
		(pad "2" smd circle
			(at 0.40005 0)
			(size 0 0)
			(layers "F.Cu" "F.Mask" "F.Paste")
			(net "GND")
		)
	)
	(footprint ""
		(layer "F.Cu")
		(at 350.380554 -86.073234)
		(property "Reference" "R1594"
			(at 0 0 0)
			(layer "F.SilkS")
			(hide yes)
			(effects
				(font
					(size 1.27 1.27)
				)
			)
		)
		(property "Value" ""
			(at 0 0 0)
			(layer "F.Fab")
			(effects
				(font
					(size 1.27 1.27)
				)
			)
		)
		(duplicate_pad_numbers_are_jumpers no)
		(fp_line
			(start -0.7874 -0.4064)
			(end 0.7874 -0.4064)
			(stroke
				(width 0.1524)
				(type default)
			)
			(layer "F.SilkS")
		)
		(fp_line
			(start -0.7874 0.4064)
			(end -0.7874 -0.4064)
			(stroke
				(width 0.1524)
				(type default)
			)
			(layer "F.SilkS")
		)
		(fp_line
			(start 0.7874 -0.4064)
			(end 0.7874 0.4064)
			(stroke
				(width 0.1524)
				(type default)
			)
			(layer "F.SilkS")
		)
		(fp_line
			(start 0.7874 0.4064)
			(end -0.7874 0.4064)
			(stroke
				(width 0.1524)
				(type default)
			)
			(layer "F.SilkS")
		)
		(fp_line
			(start -0.67945 -0.305054)
			(end -0.12065 -0.305054)
			(stroke
				(width 0.1)
				(type default)
			)
			(layer "F.Fab")
		)
		(fp_line
			(start -0.67945 0.3048)
			(end -0.67945 -0.305054)
			(stroke
				(width 0.1)
				(type default)
			)
			(layer "F.Fab")
		)
		(fp_line
			(start -0.12065 -0.305054)
			(end -0.12065 -0.2794)
			(stroke
				(width 0.1)
				(type default)
			)
			(layer "F.Fab")
		)
		(fp_line
			(start -0.12065 -0.2794)
			(end 0.12065 -0.2794)
			(stroke
				(width 0.1)
				(type default)
			)
			(layer "F.Fab")
		)
		(fp_line
			(start -0.12065 0.2794)
			(end -0.12065 0.3048)
			(stroke
				(width 0.1)
				(type default)
			)
			(layer "F.Fab")
		)
		(fp_line
			(start -0.12065 0.3048)
			(end -0.67945 0.3048)
			(stroke
				(width 0.1)
				(type default)
			)
			(layer "F.Fab")
		)
		(fp_line
			(start 0.120396 0.2794)
			(end -0.12065 0.2794)
			(stroke
				(width 0.1)
				(type default)
			)
			(layer "F.Fab")
		)
		(fp_line
			(start 0.120396 0.3048)
			(end 0.120396 0.2794)
			(stroke
				(width 0.1)
				(type default)
			)
			(layer "F.Fab")
		)
		(fp_line
			(start 0.12065 -0.3048)
			(end 0.67945 -0.3048)
			(stroke
				(width 0.1)
				(type default)
			)
			(layer "F.Fab")
		)
		(fp_line
			(start 0.12065 -0.2794)
			(end 0.12065 -0.3048)
			(stroke
				(width 0.1)
				(type default)
			)
			(layer "F.Fab")
		)
		(fp_line
			(start 0.67945 -0.3048)
			(end 0.67945 0.3048)
			(stroke
				(width 0.1)
				(type default)
			)
			(layer "F.Fab")
		)
		(fp_line
			(start 0.67945 0.3048)
			(end 0.120396 0.3048)
			(stroke
				(width 0.1)
				(type default)
			)
			(layer "F.Fab")
		)
		(pad "1" smd circle
			(at -0.40005 0)
			(size 0 0)
			(layers "F.Cu" "F.Mask" "F.Paste")
			(net "P3V3_AUX")
		)
		(pad "2" smd circle
			(at 0.40005 0)
			(size 0 0)
			(layers "F.Cu" "F.Mask" "F.Paste")
			(net "SMB_BIC_I2C9_MUX1_SSD9_R_SCL")
		)
	)
	(footprint ""
		(layer "F.Cu")
		(at 7.613396 -140.392404 180)
		(property "Reference" "PC314"
			(at 0 0 180)
			(layer "F.SilkS")
			(hide yes)
			(effects
				(font
					(size 1.27 1.27)
				)
			)
		)
		(property "Value" ""
			(at 0 0 180)
			(layer "F.Fab")
			(effects
				(font
					(size 1.27 1.27)
				)
			)
		)
		(duplicate_pad_numbers_are_jumpers no)
		(fp_line
			(start 0.7874 0.4064)
			(end -0.7874 0.4064)
			(stroke
				(width 0.1524)
				(type default)
			)
			(layer "F.SilkS")
		)
		(fp_line
			(start 0.7874 -0.4064)
			(end 0.7874 0.4064)
			(stroke
				(width 0.1524)
				(type default)
			)
			(layer "F.SilkS")
		)
		(fp_line
			(start -0.7874 0.4064)
			(end -0.7874 -0.4064)
			(stroke
				(width 0.1524)
				(type default)
			)
			(layer "F.SilkS")
		)
		(fp_line
			(start -0.7874 -0.4064)
			(end 0.7874 -0.4064)
			(stroke
				(width 0.1524)
				(type default)
			)
			(layer "F.SilkS")
		)
		(fp_line
			(start 0.67945 0.3048)
			(end 0.120396 0.3048)
			(stroke
				(width 0.1)
				(type default)
			)
			(layer "F.Fab")
		)
		(fp_line
			(start 0.67945 -0.3048)
			(end 0.67945 0.3048)
			(stroke
				(width 0.1)
				(type default)
			)
			(layer "F.Fab")
		)
		(fp_line
			(start 0.12065 -0.2794)
			(end 0.12065 -0.3048)
			(stroke
				(width 0.1)
				(type default)
			)
			(layer "F.Fab")
		)
		(fp_line
			(start 0.12065 -0.3048)
			(end 0.67945 -0.3048)
			(stroke
				(width 0.1)
				(type default)
			)
			(layer "F.Fab")
		)
		(fp_line
			(start 0.120396 0.3048)
			(end 0.120396 0.2794)
			(stroke
				(width 0.1)
				(type default)
			)
			(layer "F.Fab")
		)
		(fp_line
			(start 0.120396 0.2794)
			(end -0.12065 0.2794)
			(stroke
				(width 0.1)
				(type default)
			)
			(layer "F.Fab")
		)
		(fp_line
			(start -0.12065 0.3048)
			(end -0.67945 0.3048)
			(stroke
				(width 0.1)
				(type default)
			)
			(layer "F.Fab")
		)
		(fp_line
			(start -0.12065 0.2794)
			(end -0.12065 0.3048)
			(stroke
				(width 0.1)
				(type default)
			)
			(layer "F.Fab")
		)
		(fp_line
			(start -0.12065 -0.2794)
			(end 0.12065 -0.2794)
			(stroke
				(width 0.1)
				(type default)
			)
			(layer "F.Fab")
		)
		(fp_line
			(start -0.12065 -0.305054)
			(end -0.12065 -0.2794)
			(stroke
				(width 0.1)
				(type default)
			)
			(layer "F.Fab")
		)
		(fp_line
			(start -0.67945 0.3048)
			(end -0.67945 -0.305054)
			(stroke
				(width 0.1)
				(type default)
			)
			(layer "F.Fab")
		)
		(fp_line
			(start -0.67945 -0.305054)
			(end -0.12065 -0.305054)
			(stroke
				(width 0.1)
				(type default)
			)
			(layer "F.Fab")
		)
		(pad "1" smd circle
			(at -0.40005 0 180)
			(size 0 0)
			(layers "F.Cu" "F.Mask" "F.Paste")
			(net "P12V_NIC0_SS")
		)
		(pad "2" smd circle
			(at 0.40005 0 180)
			(size 0 0)
			(layers "F.Cu" "F.Mask" "F.Paste")
			(net "GND")
		)
	)
	(footprint ""
		(layer "F.Cu")
		(at 125.295152 -59.577986 90)
		(property "Reference" "PC507"
			(at 0 0 90)
			(layer "F.SilkS")
			(hide yes)
			(effects
				(font
					(size 1.27 1.27)
				)
			)
		)
		(property "Value" ""
			(at 0 0 90)
			(layer "F.Fab")
			(effects
				(font
					(size 1.27 1.27)
				)
			)
		)
		(duplicate_pad_numbers_are_jumpers no)
		(fp_line
			(start 0.7874 -0.4064)
			(end 0.7874 0.4064)
			(stroke
				(width 0.1524)
				(type default)
			)
			(layer "F.SilkS")
		)
		(fp_line
			(start -0.7874 -0.4064)
			(end 0.7874 -0.4064)
			(stroke
				(width 0.1524)
				(type default)
			)
			(layer "F.SilkS")
		)
		(fp_line
			(start 0.7874 0.4064)
			(end -0.7874 0.4064)
			(stroke
				(width 0.1524)
				(type default)
			)
			(layer "F.SilkS")
		)
		(fp_line
			(start -0.7874 0.4064)
			(end -0.7874 -0.4064)
			(stroke
				(width 0.1524)
				(type default)
			)
			(layer "F.SilkS")
		)
		(fp_line
			(start -0.12065 -0.305054)
			(end -0.12065 -0.2794)
			(stroke
				(width 0.1)
				(type default)
			)
			(layer "F.Fab")
		)
		(fp_line
			(start -0.67945 -0.305054)
			(end -0.12065 -0.305054)
			(stroke
				(width 0.1)
				(type default)
			)
			(layer "F.Fab")
		)
		(fp_line
			(start 0.67945 -0.3048)
			(end 0.67945 0.3048)
			(stroke
				(width 0.1)
				(type default)
			)
			(layer "F.Fab")
		)
		(fp_line
			(start 0.12065 -0.3048)
			(end 0.67945 -0.3048)
			(stroke
				(width 0.1)
				(type default)
			)
			(layer "F.Fab")
		)
		(fp_line
			(start 0.12065 -0.2794)
			(end 0.12065 -0.3048)
			(stroke
				(width 0.1)
				(type default)
			)
			(layer "F.Fab")
		)
		(fp_line
			(start -0.12065 -0.2794)
			(end 0.12065 -0.2794)
			(stroke
				(width 0.1)
				(type default)
			)
			(layer "F.Fab")
		)
		(fp_line
			(start 0.120396 0.2794)
			(end -0.12065 0.2794)
			(stroke
				(width 0.1)
				(type default)
			)
			(layer "F.Fab")
		)
		(fp_line
			(start -0.12065 0.2794)
			(end -0.12065 0.3048)
			(stroke
				(width 0.1)
				(type default)
			)
			(layer "F.Fab")
		)
		(fp_line
			(start 0.67945 0.3048)
			(end 0.120396 0.3048)
			(stroke
				(width 0.1)
				(type default)
			)
			(layer "F.Fab")
		)
		(fp_line
			(start 0.120396 0.3048)
			(end 0.120396 0.2794)
			(stroke
				(width 0.1)
				(type default)
			)
			(layer "F.Fab")
		)
		(fp_line
			(start -0.12065 0.3048)
			(end -0.67945 0.3048)
			(stroke
				(width 0.1)
				(type default)
			)
			(layer "F.Fab")
		)
		(fp_line
			(start -0.67945 0.3048)
			(end -0.67945 -0.305054)
			(stroke
				(width 0.1)
				(type default)
			)
			(layer "F.Fab")
		)
		(pad "1" smd circle
			(at -0.40005 0 90)
			(size 0 0)
			(layers "F.Cu" "F.Mask" "F.Paste")
			(net "P3V3_SSD4_SS")
		)
		(pad "2" smd circle
			(at 0.40005 0 90)
			(size 0 0)
			(layers "F.Cu" "F.Mask" "F.Paste")
			(net "GND")
		)
	)
)
